# SCM (Grand Teton) — schematic netlist excerpt (pin names and nets, part order shuffled) for the footprints in the layout excerpt that follows; sources: Cadence DE-HDL packaged netlist, KiCad conversion of 12092022_DA0F0TMDCD0_F0T_Management_Board_D_brd_V3_OCP.brd

C193  Q_CAP  0.1UF 25V 10% X7R  pkg 0402  page 41 : A = PVCCA_AUX_PLD ; B = GND
ME4  ME_DUMMY_SYMBOL  SNLABEL_7X7 EMPTY  pkg SNLABEL_7X7  page 59
R86  Q_RES  0 5% CHIP  pkg 0402LF  page 23 : A = P3V3_RGM ; B = V_BMC_DDC_LS_GATE

(kicad_pcb
	(version 20260206)
	(generator "pcbnew")
	(generator_version "10.0")
	(general
		(thickness 1.6)
		(legacy_teardrops no)
	)
	(paper "A4")
	(title_block
		(title "12092022_DA0F0TMDCD0_F0T_Management_Board_D_brd_V3_OCP.brd")
		(comment 1 "Grand Teton / footprints 1061-1063 of 1440")
	)
	(layers
		(0 "F.Cu" signal "TOP")
		(4 "In1.Cu" signal "GND")
		(6 "In2.Cu" signal "IN1")
		(8 "In3.Cu" signal "GND1")
		(10 "In4.Cu" signal "IN2")
		(12 "In5.Cu" signal "VCC")
		(14 "In6.Cu" signal "VCC1")
		(16 "In7.Cu" signal "IN3")
		(18 "In8.Cu" signal "GND2")
		(20 "In9.Cu" signal "IN4")
		(22 "In10.Cu" signal "GND3")
		(2 "B.Cu" signal "BOTTOM")
		(9 "F.Adhes" user "F.Adhesive")
		(11 "B.Adhes" user "B.Adhesive")
		(13 "F.Paste" user "Package Geometry/Pastemask Top")
		(15 "B.Paste" user "Package Geometry/Pastemask Bottom")
		(5 "F.SilkS" user "Ref Des/Silkscreen Top")
		(7 "B.SilkS" user "Ref Des/Silkscreen Bottom")
		(1 "F.Mask" user "Board Geometry/Soldermask Top")
		(3 "B.Mask" user "Board Geometry/Soldermask Bottom")
		(17 "Dwgs.User" user "User.Drawings")
		(19 "Cmts.User" user "User.Comments")
		(21 "Eco1.User" user "User.Eco1")
		(23 "Eco2.User" user "User.Eco2")
		(25 "Edge.Cuts" user "Board Geometry/Outline")
		(27 "Margin" user)
		(31 "F.CrtYd" user "Package Geometry/Place Bound Top")
		(29 "B.CrtYd" user "Package Geometry/Place Bound Bottom")
		(35 "F.Fab" user "Ref Des/Assembly Top")
		(33 "B.Fab" user "Ref Des/Assembly Bottom")
	)
	(footprint ""
		(layer "B.Cu")
		(at 26.533094 -19.955764 180)
		(property "Reference" "R86"
			(at 0 0 0)
			(layer "B.SilkS")
			(hide yes)
			(effects
				(font
					(size 1.27 1.27)
				)
				(justify mirror)
			)
		)
		(property "Value" ""
			(at 0 0 0)
			(layer "B.Fab")
			(effects
				(font
					(size 1.27 1.27)
				)
				(justify mirror)
			)
		)
		(duplicate_pad_numbers_are_jumpers no)
		(fp_line
			(start 0.7874 0.4064)
			(end 0.7874 -0.4064)
			(stroke
				(width 0.1524)
				(type default)
			)
			(layer "B.SilkS")
		)
		(fp_line
			(start 0.7874 -0.4064)
			(end -0.7874 -0.4064)
			(stroke
				(width 0.1524)
				(type default)
			)
			(layer "B.SilkS")
		)
		(fp_line
			(start -0.7874 0.4064)
			(end 0.7874 0.4064)
			(stroke
				(width 0.1524)
				(type default)
			)
			(layer "B.SilkS")
		)
		(fp_line
			(start -0.7874 -0.4064)
			(end -0.7874 0.4064)
			(stroke
				(width 0.1524)
				(type default)
			)
			(layer "B.SilkS")
		)
		(fp_line
			(start 0.67945 0.3048)
			(end 0.67945 -0.305054)
			(stroke
				(width 0.1)
				(type default)
			)
			(layer "B.Fab")
		)
		(fp_line
			(start 0.67945 -0.305054)
			(end 0.12065 -0.305054)
			(stroke
				(width 0.1)
				(type default)
			)
			(layer "B.Fab")
		)
		(fp_line
			(start 0.12065 0.3048)
			(end 0.67945 0.3048)
			(stroke
				(width 0.1)
				(type default)
			)
			(layer "B.Fab")
		)
		(fp_line
			(start 0.12065 0.2794)
			(end 0.12065 0.3048)
			(stroke
				(width 0.1)
				(type default)
			)
			(layer "B.Fab")
		)
		(fp_line
			(start 0.12065 -0.2794)
			(end -0.12065 -0.2794)
			(stroke
				(width 0.1)
				(type default)
			)
			(layer "B.Fab")
		)
		(fp_line
			(start 0.12065 -0.305054)
			(end 0.12065 -0.2794)
			(stroke
				(width 0.1)
				(type default)
			)
			(layer "B.Fab")
		)
		(fp_line
			(start -0.120396 0.3048)
			(end -0.120396 0.2794)
			(stroke
				(width 0.1)
				(type default)
			)
			(layer "B.Fab")
		)
		(fp_line
			(start -0.120396 0.2794)
			(end 0.12065 0.2794)
			(stroke
				(width 0.1)
				(type default)
			)
			(layer "B.Fab")
		)
		(fp_line
			(start -0.12065 -0.2794)
			(end -0.12065 -0.3048)
			(stroke
				(width 0.1)
				(type default)
			)
			(layer "B.Fab")
		)
		(fp_line
			(start -0.12065 -0.3048)
			(end -0.67945 -0.3048)
			(stroke
				(width 0.1)
				(type default)
			)
			(layer "B.Fab")
		)
		(fp_line
			(start -0.67945 0.3048)
			(end -0.120396 0.3048)
			(stroke
				(width 0.1)
				(type default)
			)
			(layer "B.Fab")
		)
		(fp_line
			(start -0.67945 -0.3048)
			(end -0.67945 0.3048)
			(stroke
				(width 0.1)
				(type default)
			)
			(layer "B.Fab")
		)
		(pad "1" smd circle
			(at 0.40005 0)
			(size 0 0)
			(layers "B.Cu" "B.Mask" "B.Paste")
			(net "P3V3_RGM")
		)
		(pad "2" smd circle
			(at -0.40005 0)
			(size 0 0)
			(layers "B.Cu" "B.Mask" "B.Paste")
			(net "V_BMC_DDC_LS_GATE")
		)
	)
	(footprint ""
		(layer "B.Cu")
		(at 11.098022 -67.644264)
		(property "Reference" "ME4"
			(at 0 0 0)
			(layer "B.SilkS")
			(hide yes)
			(effects
				(font
					(size 1.27 1.27)
				)
				(justify mirror)
			)
		)
		(property "Value" ""
			(at 0 0 0)
			(layer "B.Fab")
			(effects
				(font
					(size 1.27 1.27)
				)
				(justify mirror)
			)
		)
		(duplicate_pad_numbers_are_jumpers no)
		(fp_line
			(start -6.999986 -6.999986)
			(end -6.999986 -5.475986)
			(stroke
				(width 0.1524)
				(type default)
			)
			(layer "B.SilkS")
		)
		(fp_line
			(start -6.999986 -1.524)
			(end -6.999986 0)
			(stroke
				(width 0.1524)
				(type default)
			)
			(layer "B.SilkS")
		)
		(fp_line
			(start -6.999986 0)
			(end -5.475986 0)
			(stroke
				(width 0.1524)
				(type default)
			)
			(layer "B.SilkS")
		)
		(fp_line
			(start -5.475986 -6.999986)
			(end -6.999986 -6.999986)
			(stroke
				(width 0.1524)
				(type default)
			)
			(layer "B.SilkS")
		)
		(fp_line
			(start -1.524 -6.999986)
			(end 0 -6.999986)
			(stroke
				(width 0.1524)
				(type default)
			)
			(layer "B.SilkS")
		)
		(fp_line
			(start 0 -6.999986)
			(end 0 -5.475986)
			(stroke
				(width 0.1524)
				(type default)
			)
			(layer "B.SilkS")
		)
		(fp_line
			(start 0 -1.524)
			(end 0 0)
			(stroke
				(width 0.1524)
				(type default)
			)
			(layer "B.SilkS")
		)
		(fp_line
			(start 0 0)
			(end -1.524 0)
			(stroke
				(width 0.1524)
				(type default)
			)
			(layer "B.SilkS")
		)
		(fp_text user "S/N"
			(at -0.361188 -5.450078 0)
			(unlocked yes)
			(layer "B.SilkS")
			(effects
				(font
					(size 1.905 1.4224)
					(thickness 0.1524)
				)
				(justify left mirror)
			)
		)
	)
	(footprint ""
		(layer "B.Cu")
		(at 14.982444 -99.194112 135)
		(property "Reference" "C193"
			(at 0 0 135)
			(layer "B.SilkS")
			(hide yes)
			(effects
				(font
					(size 1.27 1.27)
				)
				(justify mirror)
			)
		)
		(property "Value" ""
			(at 0 0 135)
			(layer "B.Fab")
			(effects
				(font
					(size 1.27 1.27)
				)
				(justify mirror)
			)
		)
		(duplicate_pad_numbers_are_jumpers no)
		(fp_line
			(start 0.787389 -0.406267)
			(end -0.787389 -0.406267)
			(stroke
				(width 0.1524)
				(type default)
			)
			(layer "B.SilkS")
		)
		(fp_line
			(start 0.787389 0.406267)
			(end 0.787389 -0.406267)
			(stroke
				(width 0.1524)
				(type default)
			)
			(layer "B.SilkS")
		)
		(fp_line
			(start -0.787389 -0.406267)
			(end -0.787389 0.406267)
			(stroke
				(width 0.1524)
				(type default)
			)
			(layer "B.SilkS")
		)
		(fp_line
			(start -0.787389 0.406267)
			(end 0.787389 0.406267)
			(stroke
				(width 0.1524)
				(type default)
			)
			(layer "B.SilkS")
		)
		(fp_line
			(start 0.679446 -0.305149)
			(end 0.120695 -0.304969)
			(stroke
				(width 0.1)
				(type default)
			)
			(layer "B.Fab")
		)
		(fp_line
			(start 0.120695 -0.304969)
			(end 0.120695 -0.279466)
			(stroke
				(width 0.1)
				(type default)
			)
			(layer "B.Fab")
		)
		(fp_line
			(start 0.120695 -0.279466)
			(end -0.120695 -0.279466)
			(stroke
				(width 0.1)
				(type default)
			)
			(layer "B.Fab")
		)
		(fp_line
			(start 0.679446 0.30479)
			(end 0.679446 -0.305149)
			(stroke
				(width 0.1)
				(type default)
			)
			(layer "B.Fab")
		)
		(fp_line
			(start -0.120515 -0.30479)
			(end -0.679446 -0.30479)
			(stroke
				(width 0.1)
				(type default)
			)
			(layer "B.Fab")
		)
		(fp_line
			(start -0.120695 -0.279466)
			(end -0.120515 -0.30479)
			(stroke
				(width 0.1)
				(type default)
			)
			(layer "B.Fab")
		)
		(fp_line
			(start 0.120695 0.279466)
			(end 0.120515 0.30479)
			(stroke
				(width 0.1)
				(type default)
			)
			(layer "B.Fab")
		)
		(fp_line
			(start 0.120515 0.30479)
			(end 0.679446 0.30479)
			(stroke
				(width 0.1)
				(type default)
			)
			(layer "B.Fab")
		)
		(fp_line
			(start -0.679446 -0.30479)
			(end -0.679446 0.30479)
			(stroke
				(width 0.1)
				(type default)
			)
			(layer "B.Fab")
		)
		(fp_line
			(start -0.120335 0.279466)
			(end 0.120695 0.279466)
			(stroke
				(width 0.1)
				(type default)
			)
			(layer "B.Fab")
		)
		(fp_line
			(start -0.120515 0.30479)
			(end -0.120335 0.279466)
			(stroke
				(width 0.1)
				(type default)
			)
			(layer "B.Fab")
		)
		(fp_line
			(start -0.679446 0.30479)
			(end -0.120515 0.30479)
			(stroke
				(width 0.1)
				(type default)
			)
			(layer "B.Fab")
		)
		(pad "1" smd circle
			(at 0.40005 0 315)
			(size 0 0)
			(layers "B.Cu" "B.Mask" "B.Paste")
			(net "PVCCA_AUX_PLD")
		)
		(pad "2" smd circle
			(at -0.40005 0 315)
			(size 0 0)
			(layers "B.Cu" "B.Mask" "B.Paste")
			(net "GND")
		)
	)
)
